# T6G (Grand Teton) — schematic netlist excerpt (pin names and nets, part order shuffled) for the footprints in the layout excerpt that follows; sources: Cadence DE-HDL packaged netlist, KiCad conversion of 04192023_DAF0TMB3IC0_F0TG_MB_C_brd_V02_OCP.brd

R3863  Q_RES  0 5% EMPTY  pkg 0402LF  page 257 : A = P12V_OCP_SFF_ISENSE_MAM_MAM ; B = P12V_OCP_SFF_ISENSE_MAM
PC6603  Q_CAP  100NF 50V 10% X7R  pkg C0402  page 362 : A = P0V9_RETIMER_CPU0_VCC ; B = GND
H28  HOLE  EMPTY  pkg TH  page 230 : \1\ = NC

(kicad_pcb
	(version 20260206)
	(generator "pcbnew")
	(generator_version "10.0")
	(general
		(thickness 1.6)
		(legacy_teardrops no)
	)
	(paper "A4")
	(title_block
		(title "04192023_DAF0TMB3IC0_F0TG_MB_C_brd_V02_OCP.brd")
		(comment 1 "Grand Teton / footprints 2883-2885 of 8354")
	)
	(layers
		(0 "F.Cu" signal "TOP")
		(4 "In1.Cu" signal "GND")
		(6 "In2.Cu" signal "IN1")
		(8 "In3.Cu" signal "GND1")
		(10 "In4.Cu" signal "IN2")
		(12 "In5.Cu" signal "GND2")
		(14 "In6.Cu" signal "IN3")
		(16 "In7.Cu" signal "GND3")
		(18 "In8.Cu" signal "VCC")
		(20 "In9.Cu" signal "VCC1")
		(22 "In10.Cu" signal "GND4")
		(24 "In11.Cu" signal "IN4")
		(26 "In12.Cu" signal "GND5")
		(28 "In13.Cu" signal "IN5")
		(30 "In14.Cu" signal "GND6")
		(32 "In15.Cu" signal "IN6")
		(34 "In16.Cu" signal "GND7")
		(2 "B.Cu" signal "BOTTOM")
		(9 "F.Adhes" user "F.Adhesive")
		(11 "B.Adhes" user "B.Adhesive")
		(13 "F.Paste" user "Package Geometry/Pastemask Top")
		(15 "B.Paste" user "Package Geometry/Pastemask Bottom")
		(5 "F.SilkS" user "Ref Des/Silkscreen Top")
		(7 "B.SilkS" user "Ref Des/Silkscreen Bottom")
		(1 "F.Mask" user "Board Geometry/Soldermask Top")
		(3 "B.Mask" user "Board Geometry/Soldermask Bottom")
		(17 "Dwgs.User" user "User.Drawings")
		(19 "Cmts.User" user "User.Comments")
		(21 "Eco1.User" user "User.Eco1")
		(23 "Eco2.User" user "User.Eco2")
		(25 "Edge.Cuts" user "Board Geometry/Outline")
		(27 "Margin" user)
		(31 "F.CrtYd" user "Package Geometry/Place Bound Top")
		(29 "B.CrtYd" user "Package Geometry/Place Bound Bottom")
		(35 "F.Fab" user "Ref Des/Assembly Top")
		(33 "B.Fab" user "Ref Des/Assembly Bottom")
	)
	(footprint ""
		(layer "F.Cu")
		(at 311.541922 -33.715706)
		(property "Reference" "R3863"
			(at 0 0 0)
			(layer "F.SilkS")
			(hide yes)
			(effects
				(font
					(size 1.27 1.27)
				)
			)
		)
		(property "Value" ""
			(at 0 0 0)
			(layer "F.Fab")
			(effects
				(font
					(size 1.27 1.27)
				)
			)
		)
		(duplicate_pad_numbers_are_jumpers no)
		(fp_line
			(start -0.7874 -0.4064)
			(end 0.7874 -0.4064)
			(stroke
				(width 0.1524)
				(type default)
			)
			(layer "F.SilkS")
		)
		(fp_line
			(start -0.7874 0.4064)
			(end -0.7874 -0.4064)
			(stroke
				(width 0.1524)
				(type default)
			)
			(layer "F.SilkS")
		)
		(fp_line
			(start 0.7874 -0.4064)
			(end 0.7874 0.4064)
			(stroke
				(width 0.1524)
				(type default)
			)
			(layer "F.SilkS")
		)
		(fp_line
			(start 0.7874 0.4064)
			(end -0.7874 0.4064)
			(stroke
				(width 0.1524)
				(type default)
			)
			(layer "F.SilkS")
		)
		(fp_line
			(start -0.67945 -0.305054)
			(end -0.12065 -0.305054)
			(stroke
				(width 0.1)
				(type default)
			)
			(layer "F.Fab")
		)
		(fp_line
			(start -0.67945 0.3048)
			(end -0.67945 -0.305054)
			(stroke
				(width 0.1)
				(type default)
			)
			(layer "F.Fab")
		)
		(fp_line
			(start -0.12065 -0.305054)
			(end -0.12065 -0.2794)
			(stroke
				(width 0.1)
				(type default)
			)
			(layer "F.Fab")
		)
		(fp_line
			(start -0.12065 -0.2794)
			(end 0.12065 -0.2794)
			(stroke
				(width 0.1)
				(type default)
			)
			(layer "F.Fab")
		)
		(fp_line
			(start -0.12065 0.2794)
			(end -0.12065 0.3048)
			(stroke
				(width 0.1)
				(type default)
			)
			(layer "F.Fab")
		)
		(fp_line
			(start -0.12065 0.3048)
			(end -0.67945 0.3048)
			(stroke
				(width 0.1)
				(type default)
			)
			(layer "F.Fab")
		)
		(fp_line
			(start 0.120396 0.2794)
			(end -0.12065 0.2794)
			(stroke
				(width 0.1)
				(type default)
			)
			(layer "F.Fab")
		)
		(fp_line
			(start 0.120396 0.3048)
			(end 0.120396 0.2794)
			(stroke
				(width 0.1)
				(type default)
			)
			(layer "F.Fab")
		)
		(fp_line
			(start 0.12065 -0.3048)
			(end 0.67945 -0.3048)
			(stroke
				(width 0.1)
				(type default)
			)
			(layer "F.Fab")
		)
		(fp_line
			(start 0.12065 -0.2794)
			(end 0.12065 -0.3048)
			(stroke
				(width 0.1)
				(type default)
			)
			(layer "F.Fab")
		)
		(fp_line
			(start 0.67945 -0.3048)
			(end 0.67945 0.3048)
			(stroke
				(width 0.1)
				(type default)
			)
			(layer "F.Fab")
		)
		(fp_line
			(start 0.67945 0.3048)
			(end 0.120396 0.3048)
			(stroke
				(width 0.1)
				(type default)
			)
			(layer "F.Fab")
		)
		(pad "1" smd rect
			(at -0.40005 0 180)
			(size 0.4572 0.508)
			(layers "F.Cu" "F.Mask" "F.Paste")
			(net "P12V_OCP_SFF_ISENSE_MAM_MAM")
		)
		(pad "2" smd rect
			(at 0.40005 0 180)
			(size 0.4572 0.508)
			(layers "F.Cu" "F.Mask" "F.Paste")
			(net "P12V_OCP_SFF_ISENSE_MAM")
		)
	)
	(footprint ""
		(layer "F.Cu")
		(at 449.443602 -427.152308)
		(property "Reference" "PC6603"
			(at 0 0 0)
			(layer "F.SilkS")
			(hide yes)
			(effects
				(font
					(size 1.27 1.27)
				)
			)
		)
		(property "Value" ""
			(at 0 0 0)
			(layer "F.Fab")
			(effects
				(font
					(size 1.27 1.27)
				)
			)
		)
		(duplicate_pad_numbers_are_jumpers no)
		(fp_line
			(start -0.7874 -0.4064)
			(end 0.7874 -0.4064)
			(stroke
				(width 0.1524)
				(type default)
			)
			(layer "F.SilkS")
		)
		(fp_line
			(start -0.7874 0.4064)
			(end -0.7874 -0.4064)
			(stroke
				(width 0.1524)
				(type default)
			)
			(layer "F.SilkS")
		)
		(fp_line
			(start 0.7874 -0.4064)
			(end 0.7874 0.4064)
			(stroke
				(width 0.1524)
				(type default)
			)
			(layer "F.SilkS")
		)
		(fp_line
			(start 0.7874 0.4064)
			(end -0.7874 0.4064)
			(stroke
				(width 0.1524)
				(type default)
			)
			(layer "F.SilkS")
		)
		(fp_line
			(start -0.67945 -0.305054)
			(end -0.12065 -0.305054)
			(stroke
				(width 0.1)
				(type default)
			)
			(layer "F.Fab")
		)
		(fp_line
			(start -0.67945 0.3048)
			(end -0.67945 -0.305054)
			(stroke
				(width 0.1)
				(type default)
			)
			(layer "F.Fab")
		)
		(fp_line
			(start -0.12065 -0.305054)
			(end -0.12065 -0.2794)
			(stroke
				(width 0.1)
				(type default)
			)
			(layer "F.Fab")
		)
		(fp_line
			(start -0.12065 -0.2794)
			(end 0.12065 -0.2794)
			(stroke
				(width 0.1)
				(type default)
			)
			(layer "F.Fab")
		)
		(fp_line
			(start -0.12065 0.2794)
			(end -0.12065 0.3048)
			(stroke
				(width 0.1)
				(type default)
			)
			(layer "F.Fab")
		)
		(fp_line
			(start -0.12065 0.3048)
			(end -0.67945 0.3048)
			(stroke
				(width 0.1)
				(type default)
			)
			(layer "F.Fab")
		)
		(fp_line
			(start 0.120396 0.2794)
			(end -0.12065 0.2794)
			(stroke
				(width 0.1)
				(type default)
			)
			(layer "F.Fab")
		)
		(fp_line
			(start 0.120396 0.3048)
			(end 0.120396 0.2794)
			(stroke
				(width 0.1)
				(type default)
			)
			(layer "F.Fab")
		)
		(fp_line
			(start 0.12065 -0.3048)
			(end 0.67945 -0.3048)
			(stroke
				(width 0.1)
				(type default)
			)
			(layer "F.Fab")
		)
		(fp_line
			(start 0.12065 -0.2794)
			(end 0.12065 -0.3048)
			(stroke
				(width 0.1)
				(type default)
			)
			(layer "F.Fab")
		)
		(fp_line
			(start 0.67945 -0.3048)
			(end 0.67945 0.3048)
			(stroke
				(width 0.1)
				(type default)
			)
			(layer "F.Fab")
		)
		(fp_line
			(start 0.67945 0.3048)
			(end 0.120396 0.3048)
			(stroke
				(width 0.1)
				(type default)
			)
			(layer "F.Fab")
		)
		(pad "1" smd circle
			(at -0.40005 0)
			(size 0 0)
			(layers "F.Cu" "F.Mask" "F.Paste")
			(net "P0V9_RETIMER_CPU0_VCC")
		)
		(pad "2" smd circle
			(at 0.40005 0)
			(size 0 0)
			(layers "F.Cu" "F.Mask" "F.Paste")
			(net "GND")
		)
	)
	(footprint ""
		(layer "F.Cu")
		(at 11.176 -39.1668)
		(property "Reference" "H28"
			(at -1.16586 -4.917948 0)
			(unlocked yes)
			(layer "F.SilkS")
			(effects
				(font
					(size 0.7874 0.5842)
					(thickness 0.1524)
				)
				(justify left)
			)
		)
		(property "Value" ""
			(at 0 0 0)
			(layer "F.Fab")
			(effects
				(font
					(size 1.27 1.27)
				)
			)
		)
		(duplicate_pad_numbers_are_jumpers no)
		(fp_circle
			(center 0 0)
			(end 2.4003 0)
			(stroke
				(width 0.1524)
				(type default)
			)
			(fill no)
			(layer "F.SilkS")
		)
		(fp_arc
			(start -6.391402 1.610868)
			(mid -0.81161 -6.541116)
			(end 6.5913 0)
			(stroke
				(width 0.1524)
				(type default)
			)
			(layer "B.SilkS")
		)
		(fp_arc
			(start 6.5913 0)
			(mid 2.749338 5.990524)
			(end -4.29768 4.99745)
			(stroke
				(width 0.1524)
				(type default)
			)
			(layer "B.SilkS")
		)
		(fp_circle
			(center 0 0)
			(end 6.5913 0)
			(stroke
				(width 0.1)
				(type default)
			)
			(fill no)
			(layer "B.Fab")
		)
		(fp_circle
			(center 0 0)
			(end 2.4003 0)
			(stroke
				(width 0.1)
				(type default)
			)
			(fill no)
			(layer "F.Fab")
		)
		(pad "" np_thru_hole circle
			(at 0 0)
			(size 3.175 3.175)
			(drill 3.175)
			(layers "*.Cu" "*.Mask")
			(clearance 0.381)
			(thermal_gap 0.381)
		)
		(zone
			(layers "F.Cu" "B.Cu" "In1.Cu" "In2.Cu" "In3.Cu" "In4.Cu" "In5.Cu" "In6.Cu"
				"In7.Cu" "In8.Cu" "In9.Cu" "In10.Cu" "In11.Cu" "In12.Cu" "In13.Cu" "In14.Cu"
				"In15.Cu" "In16.Cu"
			)
			(hatch none 0.5)
			(connect_pads
				(clearance 0)
			)
			(min_thickness 0.25)
			(keepout
				(tracks not_allowed)
				(vias allowed)
				(pads allowed)
				(copperpour not_allowed)
				(footprints allowed)
			)
			(placement
				(enabled no)
				(sheetname "")
			)
			(fill
				(thermal_gap 0.5)
				(thermal_bridge_width 0.5)
				(island_removal_mode 0)
			)
			(polygon
				(pts
					(arc
						(start 13.2715 -39.1668)
						(mid 9.0805 -39.1668)
						(end 13.2715 -39.1668)
					)
				)
			)
		)
	)
)
